# S9S_MB_2U (Grand Teton) — schematic netlist excerpt (pin names and nets, part order shuffled) for the footprints in the layout excerpt that follows; sources: Cadence DE-HDL packaged netlist, KiCad conversion of 03242023_DA0F0TMBIJ0_F0T_Motherboard_J_brd_V01_OCP.brd

U240  74LVC2G08DP  IC  pkg TSSOP8_0-65_3X3  page 165
  \1a\  = OCP_SFF_PRSNT0_R_N
  \1b\  = OCP_SFF_PRSNT1_R_N
  \2y\  = OCP_SFF_PRSNT23_R_N
  GND  = GND
  \2a\  = OCP_SFF_PRSNT2_R_N
  \2b\  = OCP_SFF_PRSNT3_R_N
  \1y\  = OCP_SFF_PRSNT01_R_N
  VCC  = P3V3_AUX

R624  Q_RES  10K 1% CHIP  pkg 0402LF  page 199 : A = FM_PCH_XTALSEL ; B = GND

(kicad_pcb
	(version 20260206)
	(generator "pcbnew")
	(generator_version "10.0")
	(general
		(thickness 1.6)
		(legacy_teardrops no)
	)
	(paper "A4")
	(title_block
		(title "03242023_DA0F0TMBIJ0_F0T_Motherboard_J_brd_V01_OCP.brd")
		(comment 1 "Grand Teton / footprints 3605-3606 of 6105")
	)
	(layers
		(0 "F.Cu" signal "TOP")
		(4 "In1.Cu" signal "GND")
		(6 "In2.Cu" signal "IN1")
		(8 "In3.Cu" signal "GND1")
		(10 "In4.Cu" signal "IN2")
		(12 "In5.Cu" signal "GND2")
		(14 "In6.Cu" signal "IN3")
		(16 "In7.Cu" signal "GND3")
		(18 "In8.Cu" signal "VCC")
		(20 "In9.Cu" signal "VCC1")
		(22 "In10.Cu" signal "GND4")
		(24 "In11.Cu" signal "IN4")
		(26 "In12.Cu" signal "GND5")
		(28 "In13.Cu" signal "IN5")
		(30 "In14.Cu" signal "GND6")
		(32 "In15.Cu" signal "IN6")
		(34 "In16.Cu" signal "GND7")
		(2 "B.Cu" signal "BOTTOM")
		(9 "F.Adhes" user "F.Adhesive")
		(11 "B.Adhes" user "B.Adhesive")
		(13 "F.Paste" user "Package Geometry/Pastemask Top")
		(15 "B.Paste" user "Package Geometry/Pastemask Bottom")
		(5 "F.SilkS" user "Ref Des/Silkscreen Top")
		(7 "B.SilkS" user "Ref Des/Silkscreen Bottom")
		(1 "F.Mask" user "Board Geometry/Soldermask Top")
		(3 "B.Mask" user "Board Geometry/Soldermask Bottom")
		(17 "Dwgs.User" user "User.Drawings")
		(19 "Cmts.User" user "User.Comments")
		(21 "Eco1.User" user "User.Eco1")
		(23 "Eco2.User" user "User.Eco2")
		(25 "Edge.Cuts" user "Board Geometry/Outline")
		(27 "Margin" user)
		(31 "F.CrtYd" user "Package Geometry/Place Bound Top")
		(29 "B.CrtYd" user "Package Geometry/Place Bound Bottom")
		(35 "F.Fab" user "Ref Des/Assembly Top")
		(33 "B.Fab" user "Ref Des/Assembly Bottom")
	)
	(footprint ""
		(layer "F.Cu")
		(at 315.110622 -54.219348 180)
		(property "Reference" "R624"
			(at 0 0 180)
			(layer "F.SilkS")
			(hide yes)
			(effects
				(font
					(size 1.27 1.27)
				)
			)
		)
		(property "Value" ""
			(at 0 0 180)
			(layer "F.Fab")
			(effects
				(font
					(size 1.27 1.27)
				)
			)
		)
		(duplicate_pad_numbers_are_jumpers no)
		(fp_line
			(start 0.7874 0.4064)
			(end -0.7874 0.4064)
			(stroke
				(width 0.1524)
				(type default)
			)
			(layer "F.SilkS")
		)
		(fp_line
			(start 0.7874 -0.4064)
			(end 0.7874 0.4064)
			(stroke
				(width 0.1524)
				(type default)
			)
			(layer "F.SilkS")
		)
		(fp_line
			(start -0.7874 0.4064)
			(end -0.7874 -0.4064)
			(stroke
				(width 0.1524)
				(type default)
			)
			(layer "F.SilkS")
		)
		(fp_line
			(start -0.7874 -0.4064)
			(end 0.7874 -0.4064)
			(stroke
				(width 0.1524)
				(type default)
			)
			(layer "F.SilkS")
		)
		(fp_line
			(start 0.67945 0.3048)
			(end 0.120396 0.3048)
			(stroke
				(width 0.1)
				(type default)
			)
			(layer "F.Fab")
		)
		(fp_line
			(start 0.67945 -0.3048)
			(end 0.67945 0.3048)
			(stroke
				(width 0.1)
				(type default)
			)
			(layer "F.Fab")
		)
		(fp_line
			(start 0.12065 -0.2794)
			(end 0.12065 -0.3048)
			(stroke
				(width 0.1)
				(type default)
			)
			(layer "F.Fab")
		)
		(fp_line
			(start 0.12065 -0.3048)
			(end 0.67945 -0.3048)
			(stroke
				(width 0.1)
				(type default)
			)
			(layer "F.Fab")
		)
		(fp_line
			(start 0.120396 0.3048)
			(end 0.120396 0.2794)
			(stroke
				(width 0.1)
				(type default)
			)
			(layer "F.Fab")
		)
		(fp_line
			(start 0.120396 0.2794)
			(end -0.12065 0.2794)
			(stroke
				(width 0.1)
				(type default)
			)
			(layer "F.Fab")
		)
		(fp_line
			(start -0.12065 0.3048)
			(end -0.67945 0.3048)
			(stroke
				(width 0.1)
				(type default)
			)
			(layer "F.Fab")
		)
		(fp_line
			(start -0.12065 0.2794)
			(end -0.12065 0.3048)
			(stroke
				(width 0.1)
				(type default)
			)
			(layer "F.Fab")
		)
		(fp_line
			(start -0.12065 -0.2794)
			(end 0.12065 -0.2794)
			(stroke
				(width 0.1)
				(type default)
			)
			(layer "F.Fab")
		)
		(fp_line
			(start -0.12065 -0.305054)
			(end -0.12065 -0.2794)
			(stroke
				(width 0.1)
				(type default)
			)
			(layer "F.Fab")
		)
		(fp_line
			(start -0.67945 0.3048)
			(end -0.67945 -0.305054)
			(stroke
				(width 0.1)
				(type default)
			)
			(layer "F.Fab")
		)
		(fp_line
			(start -0.67945 -0.305054)
			(end -0.12065 -0.305054)
			(stroke
				(width 0.1)
				(type default)
			)
			(layer "F.Fab")
		)
		(pad "1" smd circle
			(at -0.40005 0 180)
			(size 0 0)
			(layers "F.Cu" "F.Mask" "F.Paste")
			(net "FM_PCH_XTALSEL")
		)
		(pad "2" smd circle
			(at 0.40005 0 180)
			(size 0 0)
			(layers "F.Cu" "F.Mask" "F.Paste")
			(net "GND")
		)
	)
	(footprint ""
		(layer "F.Cu")
		(at 444.85814 -39.512748)
		(property "Reference" "U240"
			(at -2.3876 -2.250948 0)
			(unlocked yes)
			(layer "F.SilkS")
			(effects
				(font
					(size 0.7874 0.5842)
					(thickness 0.1524)
				)
				(justify left)
			)
		)
		(property "Value" ""
			(at 0 0 0)
			(layer "F.Fab")
			(effects
				(font
					(size 1.27 1.27)
				)
			)
		)
		(duplicate_pad_numbers_are_jumpers no)
		(fp_line
			(start -1.207008 -1.549908)
			(end -1.207008 1.549908)
			(stroke
				(width 0.1524)
				(type default)
			)
			(layer "F.SilkS")
		)
		(fp_line
			(start -1.207008 1.549908)
			(end 1.207008 1.549908)
			(stroke
				(width 0.1524)
				(type default)
			)
			(layer "F.SilkS")
		)
		(fp_line
			(start -0.762508 -1.549908)
			(end -1.207008 -1.549908)
			(stroke
				(width 0.1524)
				(type default)
			)
			(layer "F.SilkS")
		)
		(fp_line
			(start 0 -0.635)
			(end -0.762508 -1.549908)
			(stroke
				(width 0.1524)
				(type default)
			)
			(layer "F.SilkS")
		)
		(fp_line
			(start 0.762508 -1.549908)
			(end 0 -0.635)
			(stroke
				(width 0.1524)
				(type default)
			)
			(layer "F.SilkS")
		)
		(fp_line
			(start 1.207008 -1.549908)
			(end 0.762508 -1.549908)
			(stroke
				(width 0.1524)
				(type default)
			)
			(layer "F.SilkS")
		)
		(fp_line
			(start 1.207008 1.549908)
			(end 1.207008 -1.549908)
			(stroke
				(width 0.1524)
				(type default)
			)
			(layer "F.SilkS")
		)
		(fp_poly
			(pts
				(xy -3.4036 -1.53289) (xy -2.3876 -1.02489) (xy -3.4036 -0.51689)
			)
			(stroke
				(width 0)
				(type default)
			)
			(fill yes)
			(layer "F.SilkS")
		)
		(fp_line
			(start -1.549908 -1.549908)
			(end -1.549908 1.549908)
			(stroke
				(width 0.1)
				(type default)
			)
			(layer "F.Fab")
		)
		(fp_line
			(start -1.549908 1.549908)
			(end 1.549908 1.549908)
			(stroke
				(width 0.1)
				(type default)
			)
			(layer "F.Fab")
		)
		(fp_line
			(start 1.549908 -1.549908)
			(end -1.549908 -1.549908)
			(stroke
				(width 0.1)
				(type default)
			)
			(layer "F.Fab")
		)
		(fp_line
			(start 1.549908 1.549908)
			(end 1.549908 -1.549908)
			(stroke
				(width 0.1)
				(type default)
			)
			(layer "F.Fab")
		)
		(fp_poly
			(pts
				(xy -3.4036 -1.53289) (xy -3.4036 -0.51689) (xy -2.3876 -1.02489)
			)
			(stroke
				(width 0)
				(type default)
			)
			(fill yes)
			(layer "F.Fab")
		)
		(pad "1" smd rect
			(at -1.774952 -1.02489 270)
			(size 0.508 0.8636)
			(layers "F.Cu" "F.Mask" "F.Paste")
			(net "OCP_SFF_PRSNT0_R_N")
		)
		(pad "2" smd rect
			(at -1.774952 -0.32512 270)
			(size 0.4064 0.8636)
			(layers "F.Cu" "F.Mask" "F.Paste")
			(net "OCP_SFF_PRSNT1_R_N")
		)
		(pad "3" smd rect
			(at -1.774952 0.32512 270)
			(size 0.4064 0.8636)
			(layers "F.Cu" "F.Mask" "F.Paste")
			(net "OCP_SFF_PRSNT23_R_N")
		)
		(pad "4" smd rect
			(at -1.774952 1.02489 270)
			(size 0.508 0.8636)
			(layers "F.Cu" "F.Mask" "F.Paste")
			(net "GND")
		)
		(pad "5" smd rect
			(at 1.774952 1.02489 270)
			(size 0.508 0.8636)
			(layers "F.Cu" "F.Mask" "F.Paste")
			(net "OCP_SFF_PRSNT2_R_N")
		)
		(pad "6" smd rect
			(at 1.774952 0.32512 270)
			(size 0.4064 0.8636)
			(layers "F.Cu" "F.Mask" "F.Paste")
			(net "OCP_SFF_PRSNT3_R_N")
		)
		(pad "7" smd rect
			(at 1.774952 -0.32512 270)
			(size 0.4064 0.8636)
			(layers "F.Cu" "F.Mask" "F.Paste")
			(net "OCP_SFF_PRSNT01_R_N")
		)
		(pad "8" smd rect
			(at 1.774952 -1.02489 270)
			(size 0.508 0.8636)
			(layers "F.Cu" "F.Mask" "F.Paste")
			(net "P3V3_AUX")
		)
	)
)
